FILE_TYPE = CONNECTIVITY;
{Allegro Design Entry HDL 17.2-2016 S066 (3851973) 4/6/2020}
"PAGE_NUMBER" = 9;
0"NC";
1"VDD_BNO085";
2"UN$9$CAPACITOR$I17$1";
3"UN$9$BNO080LGA28$I29$XOUT32";
4"UN$9$BNO080LGA28$I29$CAP";
5"UN$9$BNO080LGA28$I29$HCS";
6"FPGA_OUT_BNO080_RST_N";
7"BNO080_EVN_SCL";
8"R_BNO080_I2C_SDA";
9"R_BNO080_I2C_SCL";
10"UN$9$BNO080LGA28$I29$CLKSEL0";
11"UN$9$BNO080LGA28$I29$PS0";
12"UN$9$BNO080LGA28$I29$PS1";
13"R_BNO080_INT_N";
14"R_BNO080_BOOT_N";
15"BNO080_SA0";
16"FPGA_OUT_BNO080_BOOT_N";
17"FPGA_IN_BNO080_INT_N";
18"BNO080_I2C_SCL";
19"BNO080_I2C_SDA";
20"BNO080_EVN_SDA";
21"R_BNO080_EVN_SCL";
22"R_BNO080_EVN_SDA";
23"R_BNO080_RST_N";
24"SG\g";
25"XP3R3V_FPGA\g";
26"SG\g";
27"SG\g";
28"XP3R3V_FPGA\g";
29"XP3R3V_FPGA\g";
30"SG\g";
31"XP3R3V_FPGA\g";
%"RESISTOR"
"1","(-10200,9900)","0","passive","I11";
;
$LOCATION"R77"
CDS_LOCATION"R77"
$SEC"1"
CDS_SEC"1"
VALUE"33OHM"
PACKAGE"0402"
TOLERANCE"1%"
CLS_PN"G155-133R0-01"
SIGNAL_MODEL"DEFAULT_RESISTOR_33OHM_2_1"
CDS_LMAN_SYM_OUTLINE"-50,50,100,-50"
CDS_LIB"passive";
"1"
$PN"1"18;
"2"
$PN"2"9;
%"RESISTOR"
"1","(-10200,10000)","0","passive","I12";
;
$LOCATION"R76"
CDS_LOCATION"R76"
$SEC"1"
CDS_SEC"1"
VALUE"33OHM"
PACKAGE"0402"
TOLERANCE"1%"
CLS_PN"G155-133R0-01"
SIGNAL_MODEL"DEFAULT_RESISTOR_33OHM_2_1"
CDS_LMAN_SYM_OUTLINE"-50,50,100,-50"
CDS_LIB"passive";
"1"
$PN"1"19;
"2"
$PN"2"8;
%"GND_SG"
"1","(-3650,10350)","0","cls","I14";
;
HDL_POWER"SG"
BODY_TYPE"PLUMBING"
CDS_LIB"cls"
CDS_LMAN_SYM_OUTLINE"0,0,100,-50";
"SGND"24;
%"XTAL_2"
"1","(-4700,10100)","1","clock","I16";
;
$LOCATION"Y1"
CDS_LOCATION"Y1"
$SEC"1"
CDS_SEC"1"
CLS_PN"G131-10075-01"
PART_NUMBER"9H03200012"
CDS_LMAN_SYM_OUTLINE"0,0,200,-200"
CDS_LIB"clock";
"2"
$PN"2"2;
"1"
$PN"1"3;
%"CAPACITOR"
"2","(-4300,10450)","1","passive","I17";
;
$LOCATION"C51"
CDS_LOCATION"C51"
$SEC"1"
CDS_SEC"1"
PACKAGE"0201"
VALUE"12PF"
VOLTAGE"50V"
TOLERANCE"5%"
CLS_PN"G104-0A120-FJ"
CDS_LIB"passive"
CDS_LMAN_SYM_OUTLINE"-50,0,50,-50";
"2"
$PN"2"24;
"1"
$PN"1"2;
%"VCC"
"1","(-11550,11100)","0","cls","I18";
;
VOLTAGE"3.3V"
HDL_POWER"XP3R3V_FPGA"
CDS_LIB"cls"
CDS_LMAN_SYM_OUTLINE"-250,250,250,-250"
BODY_TYPE"PLUMBING";
"$PIN0"25;
%"GND_SG"
"1","(-8700,11200)","2","cls","I19";
;
HDL_POWER"SG"
BODY_TYPE"PLUMBING"
CDS_LIB"cls"
CDS_LMAN_SYM_OUTLINE"0,0,100,-50";
"SGND"26;
%"VCC"
"1","(-10300,12200)","0","cls","I20";
;
VOLTAGE"3.3V"
HDL_POWER"XP3R3V_FPGA"
BODY_TYPE"PLUMBING"
CDS_LIB"cls"
CDS_LMAN_SYM_OUTLINE"-250,250,250,-250";
"$PIN0"29;
%"CAPACITOR"
"2","(-10250,11700)","2","passive","I21";
;
$LOCATION"C279"
CDS_LOCATION"C279"
$SEC"1"
CDS_SEC"1"
VALUE"0.1UF"
PACKAGE"0402"
VOLTAGE"25V"
TOLERANCE"10%"
CLS_PN"G105-0B104-EK"
CDS_LMAN_SYM_OUTLINE"-50,0,50,-50"
CDS_LIB"passive";
"2"
$PN"2"26;
"1"
$PN"1"29;
%"FERRITEBEAD"
"1","(-9650,12050)","2","passive","I22";
;
$LOCATION"L19"
CDS_LOCATION"L19"
$SEC"1"
CDS_SEC"1"
DCR"1300MA 0.15OHM"
VALUE"600OHM"
PACKAGE"0603"
CDS_LMAN_SYM_OUTLINE"0,0,200,-100"
CDS_LIB"passive"
CLS_PN"G191-10097-01"
TOLERANCE"25%";
"2"
$PN"2"29;
"1"
$PN"1"1;
%"CAPACITOR"
"2","(-9200,11700)","2","passive","I23";
;
$LOCATION"C280"
CDS_LOCATION"C280"
$SEC"1"
CDS_SEC"1"
PACKAGE"0402"
VOLTAGE"6.3V"
VALUE"10UF"
TOLERANCE"20%"
CDS_LIB"passive"
CDS_LMAN_SYM_OUTLINE"-50,0,50,-50"
CLS_PN"G105-0C106-BM";
"2"
$PN"2"26;
"1"
$PN"1"1;
%"CAPACITOR"
"2","(-8750,11700)","2","passive","I24";
;
$LOCATION"C281"
CDS_LOCATION"C281"
$SEC"1"
CDS_SEC"1"
VALUE"0.1UF"
PACKAGE"0402"
VOLTAGE"25V"
CDS_LMAN_SYM_OUTLINE"-50,0,50,-50"
CDS_LIB"passive"
CLS_PN"G105-0B104-EK"
TOLERANCE"10%";
"2"
$PN"2"26;
"1"
$PN"1"1;
%"BNO080_LGA_28"
"1","(-7500,10500)","0","lsi","I29";
;
$LOCATION"U29"
CDS_LOCATION"U29"
$SEC"1"
CDS_SEC"1"
CLS_PN"A246-00002-FB"
VALUE"BNO085"
CDS_LIB"lsi"
CDS_LMAN_SYM_OUTLINE"0,0,1750,-1900";
"VDDIO"
$PN"28"1;
"XIN32"
$PN"27"2;
"XOUT32/CLKSEL1"
$PN"26"3;
"GND_2"
$PN"25"27;
"RESV_NC_9"
$PN"24"0;
"RESV_NC_8"
$PN"23"0;
"RESV_NC_7"
$PN"22"0;
"RESV_NC_6"
$PN"21"0;
"H_SDA/H_MISO/TX"
$PN"20"8;
"H_SCL/SCK/RX"
$PN"19"9;
"H_CS* \B"
$PN"18"5;
"SA0/H_MOSI"
$PN"17"15;
"ENV_SDA"
$PN"16"22;
"ENV_SCL"
$PN"15"21;
"H_INTN"
$PN"14"13;
"RESV_NC_5"
$PN"13"0;
"RESV_NC_4"
$PN"12"0;
"RST* \B"
$PN"11"23;
"CLKSEL0"
$PN"10"10;
"CAP"
$PN"9"4;
"RESV_NC_3"
$PN"8"0;
"RESV_NC_2"
$PN"7"0;
"PS0/WAKE"
$PN"6"11;
"PS1"
$PN"5"12;
"BOOTN"
$PN"4"14;
"VDD"
$PN"3"1;
"GND_1"
$PN"2"27;
"RESV_NC_1"
$PN"1"0;
%"RESISTOR"
"1","(-10200,9800)","0","passive","I31";
;
$LOCATION"R79"
CDS_LOCATION"R79"
$SEC"1"
CDS_SEC"1"
VALUE"33OHM"
PACKAGE"0402"
TOLERANCE"1%"
CLS_PN"G155-133R0-01"
SIGNAL_MODEL"DEFAULT_RESISTOR_33OHM_2_1"
CDS_LMAN_SYM_OUTLINE"-50,50,100,-50"
CDS_LIB"passive";
"1"
$PN"1"17;
"2"
$PN"2"13;
%"RESISTOR"
"1","(-10200,9700)","0","passive","I32";
;
$LOCATION"R80"
CDS_LOCATION"R80"
$SEC"1"
CDS_SEC"1"
PACKAGE"0402"
VALUE"33OHM"
TOLERANCE"1%"
CLS_PN"G155-133R0-01"
SIGNAL_MODEL"DEFAULT_RESISTOR_33OHM_2_1"
CDS_LIB"passive"
CDS_LMAN_SYM_OUTLINE"-50,50,100,-50";
"1"
$PN"1"16;
"2"
$PN"2"14;
%"RESISTOR"
"2","(-9050,10650)","0","passive","I37";
;
$LOCATION"R304"
CDS_LOCATION"R304"
$SEC"1"
CDS_SEC"1"
VALUE"4.7KOHM"
PACKAGE"0402"
TOLERANCE"1%"
CDS_LIB"passive"
CDS_LMAN_SYM_OUTLINE"-50,50,50,-100"
CLS_PN"G155-14701-01";
"1"
$PN"1"25;
"2"
$PN"2"14;
%"RESISTOR"
"2","(-10700,10700)","0","passive","I38";
;
LOCATION"R289"
$SEC"1"
CDS_SEC"1"
VALUE"4.7KOHM"
PACKAGE"0402"
TOLERANCE"1%"
CDS_LIB"passive"
CDS_LMAN_SYM_OUTLINE"-50,50,50,-100"
CLS_PN"G155-14701-01";
"1"
$PN"1"25;
"2"
$PN"2"17;
%"RESISTOR"
"1","(-2450,9700)","0","passive","I41";
;
$LOCATION"R78"
CDS_LOCATION"R78"
$SEC"1"
CDS_SEC"1"
PACKAGE"0402"
VALUE"33OHM"
TOLERANCE"1%"
CLS_PN"G155-133R0-01"
SIGNAL_MODEL"DEFAULT_RESISTOR_33OHM_2_1"
CDS_LIB"passive"
CDS_LMAN_SYM_OUTLINE"-50,50,100,-50";
"1"
$PN"1"23;
"2"
$PN"2"6;
%"RESISTOR"
"1","(-4000,9350)","5","passive","I43";
;
$LOCATION"R301"
CDS_LOCATION"R301"
$SEC"1"
CDS_SEC"1"
PACKAGE"0402"
VALUE"4.7KOHM"
NO_ASSY"TRUE"
TOLERANCE"1%"
CLS_PN"G155-14701-01"
CDS_LIB"passive"
CDS_LMAN_SYM_OUTLINE"-50,50,100,-50";
"1"
$PN"1"23;
"2"
$PN"2"30;
%"RESISTOR"
"1","(-3100,10250)","5","passive","I44";
;
$LOCATION"R291"
CDS_LOCATION"R291"
$SEC"1"
CDS_SEC"1"
VALUE"4.7KOHM"
PACKAGE"0402"
TOLERANCE"1%"
CDS_LIB"passive"
CDS_LMAN_SYM_OUTLINE"-50,50,100,-50"
CLS_PN"G155-14701-01";
"1"
$PN"1"31;
"2"
$PN"2"23;
%"GND_SG"
"1","(-4050,8950)","0","cls","I45";
;
HDL_POWER"SG"
CDS_LMAN_SYM_OUTLINE"0,0,100,-50"
CDS_LIB"cls"
BODY_TYPE"PLUMBING";
"SGND"30;
%"VCC"
"1","(-3150,10750)","0","cls","I46";
;
VOLTAGE"3.3V"
HDL_POWER"XP3R3V_FPGA"
CDS_LIB"cls"
CDS_LMAN_SYM_OUTLINE"-250,250,250,-250"
BODY_TYPE"PLUMBING";
"$PIN0"31;
%"RESISTOR"
"2","(-8400,9050)","0","passive","I47";
;
$LOCATION"R307"
CDS_LOCATION"R307"
$SEC"1"
CDS_SEC"1"
VALUE"1KOHM"
PACKAGE"0402"
CLS_PN"G155-11001-01"
TOLERANCE"1%"
CDS_LMAN_SYM_OUTLINE"-50,50,50,-100"
CDS_LIB"passive";
"1"
$PN"1"10;
"2"
$PN"2"27;
%"GND_SG"
"1","(-7850,8450)","0","cls","I48";
;
HDL_POWER"SG"
BODY_TYPE"PLUMBING"
CDS_LIB"cls"
CDS_LMAN_SYM_OUTLINE"0,0,100,-50";
"SGND"27;
%"RESISTOR"
"2","(-8750,9050)","0","passive","I49";
;
$LOCATION"R305"
CDS_LOCATION"R305"
$SEC"1"
CDS_SEC"1"
VALUE"1KOHM"
PACKAGE"0402"
TOLERANCE"1%"
CDS_LIB"passive"
CDS_LMAN_SYM_OUTLINE"-50,50,50,-100"
CLS_PN"G155-11001-01";
"1"
$PN"1"11;
"2"
$PN"2"27;
%"RESISTOR"
"2","(-9100,9050)","0","passive","I50";
;
$LOCATION"R303"
CDS_LOCATION"R303"
$SEC"1"
CDS_SEC"1"
VALUE"1KOHM"
PACKAGE"0402"
TOLERANCE"1%"
CLS_PN"G155-11001-01"
CDS_LIB"passive"
CDS_LMAN_SYM_OUTLINE"-50,50,50,-100";
"1"
$PN"1"12;
"2"
$PN"2"27;
%"RESISTOR"
"2","(-9450,10650)","0","passive","I51";
;
LOCATION"R290"
$SEC"1"
CDS_SEC"1"
VALUE"4.7KOHM"
PACKAGE"0402"
NO_ASSY"TRUE"
TOLERANCE"1%"
CLS_PN"G155-14701-01"
CDS_LMAN_SYM_OUTLINE"-50,50,50,-100"
CDS_LIB"passive";
"1"
$PN"1"25;
"2"
$PN"2"15;
%"RESISTOR"
"2","(-9450,9050)","0","passive","I52";
;
$LOCATION"R302"
CDS_LOCATION"R302"
$SEC"1"
CDS_SEC"1"
VALUE"1KOHM"
PACKAGE"0402"
TOLERANCE"1%"
CLS_PN"G155-11001-01"
CDS_LMAN_SYM_OUTLINE"-50,50,50,-100"
CDS_LIB"passive";
"1"
$PN"1"15;
"2"
$PN"2"27;
%"CAPACITOR"
"2","(-4800,10700)","1","passive","I53";
;
$LOCATION"C285"
CDS_LOCATION"C285"
$SEC"1"
CDS_SEC"1"
VALUE"0.1UF"
VOLTAGE"10V"
PACKAGE"0402"
CDS_LIB"passive"
CDS_LMAN_SYM_OUTLINE"-50,0,50,-50"
CLS_PN"G105-0B104-CK"
TOLERANCE"10%";
"2"
$PN"2"24;
"1"
$PN"1"4;
%"CAPACITOR"
"2","(-4300,9900)","1","passive","I54";
;
LOCATION"C47"
$SEC"1"
CDS_SEC"1"
VALUE"12PF"
PACKAGE"0201"
VOLTAGE"50V"
TOLERANCE"5%"
CLS_PN"G104-0A120-FJ"
CDS_LIB"passive"
CDS_LMAN_SYM_OUTLINE"-50,0,50,-50";
"2"
$PN"2"24;
"1"
$PN"1"3;
%"RESISTOR"
"2","(-8650,10650)","0","passive","I55";
;
$LOCATION"R306"
CDS_LOCATION"R306"
$SEC"1"
CDS_SEC"1"
PACKAGE"0402"
VALUE"4.7KOHM"
NO_ASSY"TRUE"
TOLERANCE"1%"
CDS_LIB"passive"
CDS_LMAN_SYM_OUTLINE"-50,50,50,-100"
CLS_PN"G155-14701-01";
"1"
$PN"1"25;
"2"
$PN"2"10;
%"VCC"
"1","(-2650,9050)","0","cls","I57";
;
HDL_POWER"XP3R3V_FPGA"
VOLTAGE"3.3V"
CDS_LMAN_SYM_OUTLINE"-250,250,250,-250"
CDS_LIB"cls"
BODY_TYPE"PLUMBING";
"$PIN0"28;
%"RESISTOR"
"2","(-11500,10700)","0","passive","I6";
;
$LOCATION"R74"
CDS_LOCATION"R74"
$SEC"1"
CDS_SEC"1"
VALUE"4.7KOHM"
PACKAGE"0402"
TOLERANCE"1%"
CDS_LMAN_SYM_OUTLINE"-50,50,50,-100"
CDS_LIB"passive"
CLS_PN"G155-14701-01";
"1"
$PN"1"25;
"2"
$PN"2"19;
%"TP_PIONT"
"1","(-7850,9200)","2","cls","I63";
;
$LOCATION"TP61"
CDS_LOCATION"TP61"
$SEC"1"
CDS_SEC"1"
JEDEC_TYPE"TP010CT020B030_PTH"
BOM_IGNORE"TRUE"
CDS_LMAN_SYM_OUTLINE"-50,50,50,-50"
CDS_LIB"cls";
"1 \B"
$PN"1"5;
%"RESISTOR"
"1","(-3850,8350)","0","passive","I64";
;
$LOCATION"R330"
CDS_LOCATION"R330"
$SEC"1"
CDS_SEC"1"
VALUE"33OHM"
PACKAGE"0402"
TOLERANCE"1%"
CLS_PN"G155-133R0-01"
CDS_LMAN_SYM_OUTLINE"-50,50,100,-50"
CDS_LIB"passive"
SIGNAL_MODEL"DEFAULT_RESISTOR_33OHM_2_1";
"1"
$PN"1"22;
"2"
$PN"2"20;
%"RESISTOR"
"1","(-3100,8700)","5","passive","I65";
;
$LOCATION"R341"
CDS_LOCATION"R341"
$SEC"1"
CDS_SEC"1"
PACKAGE"0402"
VALUE"4.7KOHM"
TOLERANCE"1%"
CDS_LIB"passive"
CDS_LMAN_SYM_OUTLINE"-50,50,100,-50"
CLS_PN"G155-14701-01";
"1"
$PN"1"28;
"2"
$PN"2"20;
%"RESISTOR"
"1","(-2600,8700)","5","passive","I66";
;
$LOCATION"R342"
CDS_LOCATION"R342"
$SEC"1"
CDS_SEC"1"
PACKAGE"0402"
VALUE"4.7KOHM"
CLS_PN"G155-14701-01"
CDS_LMAN_SYM_OUTLINE"-50,50,100,-50"
CDS_LIB"passive"
TOLERANCE"1%";
"1"
$PN"1"28;
"2"
$PN"2"7;
%"RESISTOR"
"1","(-3850,8250)","0","passive","I67";
;
$LOCATION"R363"
CDS_LOCATION"R363"
$SEC"1"
CDS_SEC"1"
PACKAGE"0402"
VALUE"33OHM"
TOLERANCE"1%"
CLS_PN"G155-133R0-01"
CDS_LIB"passive"
CDS_LMAN_SYM_OUTLINE"-50,50,100,-50"
SIGNAL_MODEL"DEFAULT_RESISTOR_33OHM_2_1";
"1"
$PN"1"21;
"2"
$PN"2"7;
%"RESISTOR"
"2","(-11100,10700)","0","passive","I7";
;
$LOCATION"R75"
CDS_LOCATION"R75"
$SEC"1"
CDS_SEC"1"
VALUE"4.7KOHM"
PACKAGE"0402"
TOLERANCE"1%"
CLS_PN"G155-14701-01"
CDS_LIB"passive"
CDS_LMAN_SYM_OUTLINE"-50,50,50,-100";
"1"
$PN"1"25;
"2"
$PN"2"18;
%"RESISTOR"
"2","(-5150,10200)","0","passive","I70";
;
$LOCATION"R168"
CDS_LOCATION"R168"
$SEC"1"
CDS_SEC"1"
PACKAGE"0402"
VALUE"1MOHM"
NO_ASSY"TRUE"
CDS_LIB"passive"
CDS_LMAN_SYM_OUTLINE"-50,50,50,-100"
TOLERANCE"1%"
CLS_PN"G155-11004-01";
"1"
$PN"1"2;
"2"
$PN"2"3;
%"TP_PIONT"
"1","(-1550,8350)","0","cls","I71";
;
$LOCATION"TP1"
CDS_LOCATION"TP1"
$SEC"1"
CDS_SEC"1"
CDS_LIB"cls"
CDS_LMAN_SYM_OUTLINE"-50,50,50,-50"
BOM_IGNORE"TRUE"
JEDEC_TYPE"TP010CT020B030_PTH";
"1 \B"
$PN"1"20;
%"TP_PIONT"
"1","(-1550,8250)","0","cls","I72";
;
$LOCATION"TP2"
CDS_LOCATION"TP2"
$SEC"1"
CDS_SEC"1"
CDS_LIB"cls"
CDS_LMAN_SYM_OUTLINE"-50,50,50,-50"
BOM_IGNORE"TRUE"
JEDEC_TYPE"TP010CT020B030_PTH";
"1 \B"
$PN"1"7;
END.
